# TIMECARD (Time Appliance Project (Time Card)) — schematic netlist excerpt (pin names and nets, part order shuffled) for the footprints in the layout excerpt that follows; sources: Cadence DE-HDL packaged netlist, KiCad conversion of R4006-B0001-02_R01.brd

J11  CONN_USB_1X5_G2_GH4_F_RA_SMT  1050171001  pkg S_F_USB_1X5_G2_GH4_RA_P0256  page 21
  \1\  = XP5R0V_USB_CONN
  \2\  = CONN_MICRO_USB_DM
  \3\  = CONN_MICRO_USB_DP
  \4\  = NC
  \5\  = SG
  G1  = SG
  G2  = SG
  GH1  = SG
  GH2  = SG
  GH3  = SG
  GH4  = SG

(kicad_pcb
	(version 20260206)
	(generator "pcbnew")
	(generator_version "10.0")
	(general
		(thickness 1.6)
		(legacy_teardrops no)
	)
	(paper "A4")
	(title_block
		(title "timecard-production-celestica-r4006 — R4006-B0001-02_R01.brd")
		(comment 1 "Time Appliance Project (Time Card) / footprints 128-128 of 1113")
	)
	(layers
		(0 "F.Cu" signal "TOP")
		(4 "In1.Cu" signal "L02_GND1")
		(6 "In2.Cu" signal "L03_SIG1")
		(8 "In3.Cu" signal "L04_GND2")
		(10 "In4.Cu" signal "L05_VCC1")
		(12 "In5.Cu" signal "L06_VCC2")
		(14 "In6.Cu" signal "L07_GND3")
		(16 "In7.Cu" signal "L08_SIG2")
		(18 "In8.Cu" signal "L09_GND4")
		(2 "B.Cu" signal "BOTTOM")
		(9 "F.Adhes" user "F.Adhesive")
		(11 "B.Adhes" user "B.Adhesive")
		(13 "F.Paste" user "Package Geometry/Pastemask Top")
		(15 "B.Paste" user "Package Geometry/Pastemask Bottom")
		(5 "F.SilkS" user "Ref Des/Silkscreen Top")
		(7 "B.SilkS" user "Ref Des/Silkscreen Bottom")
		(1 "F.Mask" user "Board Geometry/Soldermask Top")
		(3 "B.Mask" user "Board Geometry/Soldermask Bottom")
		(17 "Dwgs.User" user "User.Drawings")
		(19 "Cmts.User" user "User.Comments")
		(21 "Eco1.User" user "User.Eco1")
		(23 "Eco2.User" user "User.Eco2")
		(25 "Edge.Cuts" user "Board Geometry/Outline")
		(27 "Margin" user)
		(31 "F.CrtYd" user "Package Geometry/Place Bound Top")
		(29 "B.CrtYd" user "Package Geometry/Place Bound Bottom")
		(35 "F.Fab" user "Ref Des/Assembly Top")
		(33 "B.Fab" user "Ref Des/Assembly Bottom")
	)
	(footprint ""
		(layer "F.Cu")
		(at 163.926774 -53.600096 90)
		(property "Reference" "J11"
			(at 5.12953 0.284226 0)
			(unlocked yes)
			(layer "F.SilkS")
			(effects
				(font
					(size 0.7874 0.5842)
					(thickness 0.1524)
				)
			)
		)
		(property "Value" ""
			(at 0 0 90)
			(layer "F.Fab")
			(effects
				(font
					(size 1.27 1.27)
				)
			)
		)
		(property "User Part Number" "PARTNUM*"
			(at 0.205486 7.130034 90)
			(unlocked yes)
			(layer "Cmts.User")
			(hide yes)
			(effects
				(font
					(size 0.7874 0.5842)
					(thickness 0.1524)
				)
			)
		)
		(property "Device Type" "CONN_USB_1X5_G2_GH4_F_RA_SMT-GA"
			(at 0.205486 5.936234 90)
			(unlocked yes)
			(layer "F.Fab")
			(hide yes)
			(effects
				(font
					(size 0.7874 0.5842)
					(thickness 0.1524)
				)
			)
		)
		(duplicate_pad_numbers_are_jumpers no)
		(fp_line
			(start 4.354068 -2.102866)
			(end 4.354068 4.129024)
			(stroke
				(width 0.1)
				(type default)
			)
			(layer "F.SilkS")
		)
		(fp_line
			(start -4.354068 -2.102866)
			(end 4.354068 -2.102866)
			(stroke
				(width 0.1)
				(type default)
			)
			(layer "F.SilkS")
		)
		(fp_line
			(start 4.354068 4.129024)
			(end -4.354068 4.129024)
			(stroke
				(width 0.1)
				(type default)
			)
			(layer "F.SilkS")
		)
		(fp_line
			(start -4.354068 4.129024)
			(end -4.354068 -2.102866)
			(stroke
				(width 0.1)
				(type default)
			)
			(layer "F.SilkS")
		)
		(fp_rect
			(start -9.18972 -6.928866)
			(end 9.18972 7.607554)
			(stroke
				(width 0)
				(type default)
			)
			(fill no)
			(layer "B.CrtYd")
		)
		(fp_rect
			(start -4.608068 -2.356866)
			(end 4.608068 4.383024)
			(stroke
				(width 0)
				(type default)
			)
			(fill no)
			(layer "F.CrtYd")
		)
		(fp_line
			(start 3.849878 -1.42494)
			(end 3.849878 3.875024)
			(stroke
				(width 0.1)
				(type default)
			)
			(layer "F.Fab")
		)
		(fp_line
			(start -3.849878 -1.42494)
			(end 3.849878 -1.42494)
			(stroke
				(width 0.1)
				(type default)
			)
			(layer "F.Fab")
		)
		(fp_line
			(start 3.849878 3.875024)
			(end -3.849878 3.875024)
			(stroke
				(width 0.1)
				(type default)
			)
			(layer "F.Fab")
		)
		(fp_line
			(start -3.849878 3.875024)
			(end -3.849878 -1.42494)
			(stroke
				(width 0.1)
				(type default)
			)
			(layer "F.Fab")
		)
		(fp_text user "1"
			(at -1.442466 -2.636774 0)
			(unlocked yes)
			(layer "F.SilkS")
			(effects
				(font
					(size 0.7874 0.5842)
					(thickness 0.1524)
				)
			)
		)
		(fp_text user "5"
			(at 1.986534 -2.509774 0)
			(unlocked yes)
			(layer "F.SilkS")
			(effects
				(font
					(size 0.7874 0.5842)
					(thickness 0.1524)
				)
			)
		)
		(fp_text user "GH2"
			(at 5.6769 -1.708404 90)
			(unlocked yes)
			(layer "F.SilkS")
			(effects
				(font
					(size 0.7874 0.5842)
					(thickness 0.1524)
				)
			)
		)
		(fp_text user "GH1"
			(at -5.467096 -1.581404 90)
			(unlocked yes)
			(layer "F.SilkS")
			(effects
				(font
					(size 0.7874 0.5842)
					(thickness 0.1524)
				)
			)
		)
		(fp_text user "GH3"
			(at -5.467096 1.720596 90)
			(unlocked yes)
			(layer "F.SilkS")
			(effects
				(font
					(size 0.7874 0.5842)
					(thickness 0.1524)
				)
			)
		)
		(fp_text user "GH4"
			(at 5.6769 1.974596 90)
			(unlocked yes)
			(layer "F.SilkS")
			(effects
				(font
					(size 0.7874 0.5842)
					(thickness 0.1524)
				)
			)
		)
		(fp_text user "1"
			(at -1.403096 -2.343404 90)
			(unlocked yes)
			(layer "F.Fab")
			(effects
				(font
					(size 0.7874 0.5842)
					(thickness 0.1524)
				)
			)
		)
		(fp_text user "5"
			(at 1.430274 -2.29997 90)
			(unlocked yes)
			(layer "F.Fab")
			(effects
				(font
					(size 0.7874 0.5842)
					(thickness 0.1524)
				)
			)
		)
		(fp_text user "GH1"
			(at -2.806954 -2.080768 90)
			(unlocked yes)
			(layer "F.Fab")
			(effects
				(font
					(size 0.7874 0.5842)
					(thickness 0.1524)
				)
			)
		)
		(fp_text user "GH2"
			(at 3.168904 -1.962404 90)
			(unlocked yes)
			(layer "F.Fab")
			(effects
				(font
					(size 0.7874 0.5842)
					(thickness 0.1524)
				)
			)
		)
		(fp_text user "GH4"
			(at 5.2959 2.088896 90)
			(unlocked yes)
			(layer "F.Fab")
			(effects
				(font
					(size 0.7874 0.5842)
					(thickness 0.1524)
				)
			)
		)
		(fp_text user "GH3"
			(at -5.2451 2.215896 90)
			(unlocked yes)
			(layer "F.Fab")
			(effects
				(font
					(size 0.7874 0.5842)
					(thickness 0.1524)
				)
			)
		)
		(fp_text user "G2"
			(at 1.14935 3.052318 90)
			(unlocked yes)
			(layer "F.Fab")
			(effects
				(font
					(size 0.7874 0.5842)
					(thickness 0.1524)
				)
			)
		)
		(fp_text user "G1"
			(at -0.88773 3.07086 90)
			(unlocked yes)
			(layer "F.Fab")
			(effects
				(font
					(size 0.7874 0.5842)
					(thickness 0.1524)
				)
			)
		)
		(pad "1" smd rect
			(at -1.299972 -1.100074 90)
			(size 0.4064 1.3462)
			(layers "F.Cu" "F.Mask" "F.Paste")
			(net "XP5R0V_USB_CONN")
		)
		(pad "2" smd rect
			(at -0.649986 -1.100074 90)
			(size 0.4064 1.3462)
			(layers "F.Cu" "F.Mask" "F.Paste")
			(net "CONN_MICRO_USB_DM")
		)
		(pad "3" smd rect
			(at 0 -1.100074 90)
			(size 0.4064 1.3462)
			(layers "F.Cu" "F.Mask" "F.Paste")
			(net "CONN_MICRO_USB_DP")
		)
		(pad "4" smd rect
			(at 0.649986 -1.100074 90)
			(size 0.4064 1.3462)
			(layers "F.Cu" "F.Mask" "F.Paste")
			(net "Net_748")
		)
		(pad "5" smd rect
			(at 1.299972 -1.100074 90)
			(size 0.4064 1.3462)
			(layers "F.Cu" "F.Mask" "F.Paste")
			(net "SG")
		)
		(pad "G1" smd rect
			(at -0.999998 1.575054 90)
			(size 1.4986 1.905)
			(layers "F.Cu" "F.Mask" "F.Paste")
			(net "SG")
		)
		(pad "G2" smd rect
			(at 0.999998 1.575054 90)
			(size 1.4986 1.905)
			(layers "F.Cu" "F.Mask" "F.Paste")
			(net "SG")
		)
		(pad "GH1" thru_hole circle
			(at -2.500122 -1.124966 90)
			(size 1.4478 1.4478)
			(drill 0.8382)
			(layers "*.Cu" "*.Mask")
			(remove_unused_layers no)
			(net "SG")
			(padstack
				(mode front_inner_back)
				(layer "Inner"
					(shape circle)
					(size 1.4478 1.4478)
					(clearance -0.0127)
				)
				(layer "B.Cu"
					(shape circle)
					(size 1.4478 1.4478)
				)
			)
		)
		(pad "GH2" thru_hole circle
			(at 2.500122 -1.124966 90)
			(size 1.4478 1.4478)
			(drill 0.8382)
			(layers "*.Cu" "*.Mask")
			(remove_unused_layers no)
			(net "SG")
			(padstack
				(mode front_inner_back)
				(layer "Inner"
					(shape circle)
					(size 1.4478 1.4478)
					(clearance -0.0127)
				)
				(layer "B.Cu"
					(shape circle)
					(size 1.4478 1.4478)
				)
			)
		)
		(pad "GH3" thru_hole circle
			(at -3.50012 1.575054 90)
			(size 0 0)
			(drill oval 0.6096 1.2954)
			(layers "*.Cu" "*.Mask")
			(remove_unused_layers no)
			(net "SG")
			(padstack
				(mode front_inner_back)
				(layer "Inner"
					(shape oval)
					(size 1.2192 1.905)
					(clearance -0.0127)
				)
				(layer "B.Cu"
					(shape oval)
					(size 1.2192 1.905)
				)
			)
		)
		(pad "GH4" thru_hole circle
			(at 3.50012 1.575054 90)
			(size 0 0)
			(drill oval 0.6096 1.2954)
			(layers "*.Cu" "*.Mask")
			(remove_unused_layers no)
			(net "SG")
			(padstack
				(mode front_inner_back)
				(layer "Inner"
					(shape oval)
					(size 1.2192 1.905)
					(clearance -0.0127)
				)
				(layer "B.Cu"
					(shape oval)
					(size 1.2192 1.905)
				)
			)
		)
	)
)
